FILE_TYPE = CONNECTIVITY;
{Allegro Design Entry HDL 16.6-p007 (v16-6-112F) 10/10/2012}
"PAGE_NUMBER" = 48;
0"NC";
1"M_C_DQS_DP<17:0>";
2"M_C_DQS_DN<17:0>";
3"M_C_MA<17:0>";
4"M_C_DQ<63:0>";
5"M_C_CLK_DN<3:0>";
6"M_C_CKE<3:0>";
7"M_C_ODT<3:0>";
8"M_C_CS_N<7:0>";
9"M_C_BA<1:0>";
10"M_C_BG<1:0>";
11"M_C_CLK_DP<3:0>";
12"M_C_ECC<7:0>";
13"PVTT_ABC\g";
14"PVDDQ_ABC\g";
15"GND\g";
16"GND\g";
17"PVPP_ABC\g";
18"PVPP_ABC\g";
19"GND\g";
20"P12V_NVDIMM_ABC\g";
21"GND\g";
22"M_C_VREF";
23"TP_CH_C_DIMM_C1_RFU_2";
24"TP_CH_C_DIMM_C1_RFU_0";
25"TP_CH_C_DIMM_C1_RFU_1";
26"SMB_DDR_ABC_VPP_SCL";
27"SMB_DDR_ABC_VPP_SDA";
28"FM_ADR_COMPLETE_ABC_N";
29"FM_DIMM_EVENT_COD_N";
30"M_C_PAR";
31"M_ABC_RST_N";
32"M_C_BA<1>";
33"M_C_CLK_DN<3>";
34"M_C_CLK_DP<2>";
35"M_C_CS_N<6>";
36"M_C_CS_N<5>";
37"M_C_MA<0>";
38"M_C_MA<1>";
39"M_C_ECC<6>";
40"M_C_ECC<5>";
41"M_C_ECC<4>";
42"M_C_ECC<3>";
43"M_C_ECC<2>";
44"M_C_ECC<1>";
45"M_C_ECC<0>";
46"M_C_CKE<3>";
47"M_C_CLK_DP<3>";
48"M_C_BG<0>";
49"M_C_BG<1>";
50"M_C_BA<0>";
51"M_C_ECC<7>";
52"M_C_ODT<2>";
53"M_C_CS_N<4>";
54"M_C_ODT<3>";
55"M_C_CKE<2>";
56"M_C_CS_N<7>";
57"M_C_CLK_DN<2>";
58"M_C_ALERT_N";
59"M_C_ACT_N";
60"M_C_C<2>";
61"M_C_DQ<6>";
62"M_C_DQ<1>";
63"M_C_DQ<0>";
64"M_C_DQ<2>";
65"M_C_DQ<3>";
66"M_C_DQ<4>";
67"M_C_DQ<5>";
68"M_C_DQ<16>";
69"M_C_DQ<14>";
70"M_C_DQ<13>";
71"M_C_DQ<12>";
72"M_C_DQ<10>";
73"M_C_DQ<9>";
74"M_C_DQ<8>";
75"M_C_DQ<7>";
76"M_C_DQ<15>";
77"M_C_DQ<17>";
78"M_C_DQ<11>";
79"M_C_DQ<25>";
80"M_C_DQ<24>";
81"M_C_DQ<23>";
82"M_C_DQ<22>";
83"M_C_DQ<21>";
84"M_C_DQ<19>";
85"M_C_DQ<18>";
86"M_C_DQ<27>";
87"M_C_DQ<26>";
88"M_C_DQ<20>";
89"M_C_DQ<29>";
90"M_C_DQ<28>";
91"M_C_DQ<37>";
92"M_C_DQ<34>";
93"M_C_DQ<33>";
94"M_C_DQ<32>";
95"M_C_DQ<31>";
96"M_C_DQ<30>";
97"M_C_DQ<35>";
98"M_C_DQ<36>";
99"M_C_DQ<46>";
100"M_C_DQ<45>";
101"M_C_DQ<44>";
102"M_C_DQ<43>";
103"M_C_DQ<42>";
104"M_C_DQ<41>";
105"M_C_DQ<40>";
106"M_C_DQ<39>";
107"M_C_DQ<38>";
108"M_C_DQ<47>";
109"M_C_MA<12>";
110"M_C_MA<13>";
111"M_C_MA<17>";
112"M_C_MA<3>";
113"M_C_MA<4>";
114"M_C_MA<5>";
115"M_C_MA<6>";
116"M_C_MA<7>";
117"M_C_MA<8>";
118"M_C_MA<9>";
119"M_C_MA<2>";
120"M_C_MA<10>";
121"M_C_MA<11>";
122"M_C_MA<14>";
123"M_C_MA<15>";
124"M_C_MA<16>";
125"M_C_DQ<56>";
126"M_C_DQ<55>";
127"M_C_DQ<57>";
128"M_C_DQ<58>";
129"M_C_DQ<54>";
130"M_C_DQ<53>";
131"M_C_DQ<52>";
132"M_C_DQ<51>";
133"M_C_DQ<50>";
134"M_C_DQ<49>";
135"M_C_DQ<48>";
136"M_C_DQ<63>";
137"M_C_DQ<62>";
138"M_C_DQ<61>";
139"M_C_DQ<60>";
140"M_C_DQ<59>";
141"M_C_DQS_DN<0>";
142"M_C_DQS_DP<0>";
143"M_C_DQS_DN<1>";
144"M_C_DQS_DP<1>";
145"M_C_DQS_DN<2>";
146"M_C_DQS_DP<2>";
147"M_C_DQS_DN<3>";
148"M_C_DQS_DP<3>";
149"M_C_DQS_DN<4>";
150"M_C_DQS_DP<4>";
151"M_C_DQS_DN<5>";
152"M_C_DQS_DP<5>";
153"M_C_DQS_DN<6>";
154"M_C_DQS_DP<6>";
155"M_C_DQS_DN<10>";
156"M_C_DQS_DP<10>";
157"M_C_DQS_DN<11>";
158"M_C_DQS_DP<11>";
159"M_C_DQS_DN<12>";
160"M_C_DQS_DP<12>";
161"M_C_DQS_DN<13>";
162"M_C_DQS_DP<13>";
163"M_C_DQS_DN<14>";
164"M_C_DQS_DP<14>";
165"M_C_DQS_DN<15>";
166"M_C_DQS_DP<15>";
167"M_C_DQS_DN<16>";
168"M_C_DQS_DP<16>";
169"M_C_DQS_DN<17>";
170"M_C_DQS_DN<7>";
171"M_C_DQS_DP<7>";
172"M_C_DQS_DN<8>";
173"M_C_DQS_DP<8>";
174"M_C_DQS_DN<9>";
175"M_C_DQS_DP<9>";
176"M_C_DQS_DP<17>";
%"TAP"
"6","(700,4850)","2","mstr_standard","I10";
;
HDL_TAP"TRUE"
BODY_TYPE"PLUMBING"
CDS_LIB"mstr_standard";
"B \NAC \NWC"1;
"S \NAC"
BN"14"164;
%"TAP"
"6","(-1650,2100)","2","mstr_standard","I100";
;
HDL_TAP"TRUE"
BODY_TYPE"PLUMBING"
CDS_LIB"mstr_standard";
"B \NAC \NWC"4;
"S \NAC"
BN"8"74;
%"TAP"
"6","(-1650,2200)","2","mstr_standard","I101";
;
HDL_TAP"TRUE"
BODY_TYPE"PLUMBING"
CDS_LIB"mstr_standard";
"B \NAC \NWC"4;
"S \NAC"
BN"10"72;
%"TAP"
"6","(-1650,2150)","2","mstr_standard","I102";
;
HDL_TAP"TRUE"
BODY_TYPE"PLUMBING"
CDS_LIB"mstr_standard";
"B \NAC \NWC"4;
"S \NAC"
BN"9"73;
%"TAP"
"6","(-1650,1950)","2","mstr_standard","I103";
;
HDL_TAP"TRUE"
BODY_TYPE"PLUMBING"
CDS_LIB"mstr_standard";
"B \NAC \NWC"4;
"S \NAC"
BN"5"67;
%"TAP"
"6","(-1650,2000)","2","mstr_standard","I104";
;
HDL_TAP"TRUE"
BODY_TYPE"PLUMBING"
CDS_LIB"mstr_standard";
"B \NAC \NWC"4;
"S \NAC"
BN"6"61;
%"TAP"
"6","(-1650,2050)","2","mstr_standard","I105";
;
HDL_TAP"TRUE"
BODY_TYPE"PLUMBING"
CDS_LIB"mstr_standard";
"B \NAC \NWC"4;
"S \NAC"
BN"7"75;
%"TAP"
"6","(-1650,1900)","2","mstr_standard","I106";
;
HDL_TAP"TRUE"
BODY_TYPE"PLUMBING"
CDS_LIB"mstr_standard";
"B \NAC \NWC"4;
"S \NAC"
BN"4"66;
%"TAP"
"6","(-1650,1850)","2","mstr_standard","I107";
;
HDL_TAP"TRUE"
BODY_TYPE"PLUMBING"
CDS_LIB"mstr_standard";
"B \NAC \NWC"4;
"S \NAC"
BN"3"65;
%"TAP"
"6","(-1650,1750)","2","mstr_standard","I108";
;
HDL_TAP"TRUE"
BODY_TYPE"PLUMBING"
CDS_LIB"mstr_standard";
"B \NAC \NWC"4;
"S \NAC"
BN"1"62;
%"TAP"
"6","(-1650,1800)","2","mstr_standard","I109";
;
HDL_TAP"TRUE"
BODY_TYPE"PLUMBING"
CDS_LIB"mstr_standard";
"B \NAC \NWC"4;
"S \NAC"
BN"2"64;
%"TAP"
"6","(-1650,1700)","2","mstr_standard","I110";
;
HDL_TAP"TRUE"
BODY_TYPE"PLUMBING"
CDS_LIB"mstr_standard";
"B \NAC \NWC"4;
"S \NAC"
BN"0"63;
%"SCONN288_H44441003"
"1","(-2400,3200)","0","mstr_sconn","I111";
;
CDS_SEC"1"
ROOM"DDR4_CH_C1"
CDS_LOCATION"J6U2"
SEC"1"
SEC_TYPE"PIP"
CDS_LIB"mstr_sconn"
BOM_COST"MEM"
PACK_TYPE"PIP"
MATERIAL"SCONN"
PART_NUMBER"H44441-003"
LOCATION"J6U2";
"DQ<63>"
$PN"280"136;
"BA<1>"
$PN"224"32;
"CK1N"
$PN"219"33;
"CK0P"
$PN"74"34;
"S3_N_C<1>"
$PN"237"56;
"S2_N_C<0>"
$PN"93"35;
"S1_N"
$PN"89"36;
"DQ<29>"
$PN"181"89;
"DQ<28>"
$PN"36"90;
"C<2>"
$PN"235"60;
"A0"
$PN"79"37;
"A1"
$PN"72"38;
"A12"
$PN"65"109;
"A13"
$PN"232"110;
"A17"
$PN"234"111;
"A3"
$PN"71"112;
"A4"
$PN"214"113;
"A5"
$PN"213"114;
"A6"
$PN"69"115;
"A7"
$PN"211"116;
"A8"
$PN"68"117;
"A9"
$PN"66"118;
"CB<6>"
$PN"54"39;
"CB<5>"
$PN"192"40;
"CB<4>"
$PN"47"41;
"CB<3>"
$PN"201"42;
"CB<2>"
$PN"56"43;
"CB<1>"
$PN"194"44;
"CB<0>"
$PN"49"45;
"CK0N"
$PN"75"57;
"CKE<1>"
$PN"203"46;
"DQ<62>"
$PN"135"137;
"DQ<61>"
$PN"273"138;
"DQ<60>"
$PN"128"139;
"DQ<59>"
$PN"282"140;
"DQ<56>"
$PN"130"125;
"DQ<55>"
$PN"269"126;
"DQ<46>"
$PN"113"99;
"DQ<45>"
$PN"251"100;
"DQ<44>"
$PN"106"101;
"DQ<43>"
$PN"260"102;
"DQ<42>"
$PN"115"103;
"DQ<41>"
$PN"253"104;
"DQ<40>"
$PN"108"105;
"DQ<39>"
$PN"247"106;
"DQ<37>"
$PN"240"91;
"DQ<34>"
$PN"104"92;
"DQ<33>"
$PN"242"93;
"DQ<32>"
$PN"97"94;
"DQ<31>"
$PN"188"95;
"DQ<30>"
$PN"43"96;
"DQ<25>"
$PN"183"79;
"DQ<24>"
$PN"38"80;
"DQ<23>"
$PN"177"81;
"DQ<22>"
$PN"32"82;
"DQ<21>"
$PN"170"83;
"DQ<20>"
$PN"25"88;
"DQ<19>"
$PN"179"84;
"DQ<18>"
$PN"34"85;
"DQ<16>"
$PN"27"68;
"DQ<14>"
$PN"21"69;
"DQ<13>"
$PN"159"70;
"DQ<12>"
$PN"14"71;
"DQ<11>"
$PN"168"78;
"DQ<10>"
$PN"23"72;
"DQ<9>"
$PN"161"73;
"DQ<8>"
$PN"16"74;
"DQ<7>"
$PN"155"75;
"DQ<6>"
$PN"10"61;
"EVENT_N"
$PN"78"29;
"PAR"
$PN"222"30;
"RESET_N"
$PN"58"31;
"RFU<2>"
$PN"144"23;
"SCL"
$PN"141"26;
"SDA"
$PN"285"27;
"VREFCA"
$PN"146"22;
"CK1P"
$PN"218"47;
"BG<0>"
$PN"63"48;
"BG<1>"
$PN"207"49;
"BA<0>"
$PN"81"50;
"SA<0>"
$PN"139"18;
"VDDSPD"
$PN"284"18;
"SA<2>"
$PN"238"18;
"SA<1>"
$PN"140"19;
"DQ<1>"
$PN"150"62;
"DQ<0>"
$PN"5"63;
"ACT_N"
$PN"62"59;
"ALERT_N"
$PN"208"58;
"A2"
$PN"216"119;
"DQ<35>"
$PN"249"97;
"DQ<36>"
$PN"95"98;
"DQ<38>"
$PN"102"107;
"A10"
$PN"225"120;
"A11"
$PN"210"121;
"A14_WE_N"
$PN"228"122;
"A15_CAS_N"
$PN"86"123;
"A16_RAS_N"
$PN"82"124;
"CB<7>"
$PN"199"51;
"ODT<0>"
$PN"87"52;
"ODT<1>"
$PN"91"54;
"CKE<0>"
$PN"60"55;
"S0_N"
$PN"84"53;
"DQ<27>"
$PN"190"86;
"DQ<26>"
$PN"45"87;
"DQ<15>"
$PN"166"76;
"DQ<17>"
$PN"172"77;
"RFU<0>"
$PN"205"24;
"RFU<1>"
$PN"227"25;
"SAVE_N_NC"
$PN"230"28;
"DQ<57>"
$PN"275"127;
"DQ<58>"
$PN"137"128;
"DQ<54>"
$PN"124"129;
"DQ<53>"
$PN"262"130;
"DQ<52>"
$PN"117"131;
"DQ<51>"
$PN"271"132;
"DQ<50>"
$PN"126"133;
"DQ<49>"
$PN"264"134;
"DQ<48>"
$PN"119"135;
"DQ<47>"
$PN"258"108;
"DQ<2>"
$PN"12"64;
"DQ<3>"
$PN"157"65;
"DQ<4>"
$PN"3"66;
"DQ<5>"
$PN"148"67;
%"TAP"
"6","(-3150,4850)","0","mstr_standard","I112";
;
HDL_TAP"TRUE"
BODY_TYPE"PLUMBING"
CDS_LIB"mstr_standard";
"B \NAC \NWC"3;
"S \NAC"
BN"17"111;
%"TAP"
"6","(-3150,4800)","0","mstr_standard","I113";
;
HDL_TAP"TRUE"
BODY_TYPE"PLUMBING"
CDS_LIB"mstr_standard";
"B \NAC \NWC"3;
"S \NAC"
BN"16"124;
%"TAP"
"6","(-3150,4750)","0","mstr_standard","I114";
;
HDL_TAP"TRUE"
BODY_TYPE"PLUMBING"
CDS_LIB"mstr_standard";
"B \NAC \NWC"3;
"S \NAC"
BN"15"123;
%"TAP"
"6","(-3150,4700)","0","mstr_standard","I115";
;
HDL_TAP"TRUE"
BODY_TYPE"PLUMBING"
CDS_LIB"mstr_standard";
"B \NAC \NWC"3;
"S \NAC"
BN"14"122;
%"TAP"
"6","(-3150,4650)","0","mstr_standard","I116";
;
HDL_TAP"TRUE"
BODY_TYPE"PLUMBING"
CDS_LIB"mstr_standard";
"B \NAC \NWC"3;
"S \NAC"
BN"13"110;
%"TAP"
"6","(-3150,4600)","0","mstr_standard","I117";
;
HDL_TAP"TRUE"
BODY_TYPE"PLUMBING"
CDS_LIB"mstr_standard";
"B \NAC \NWC"3;
"S \NAC"
BN"12"109;
%"TAP"
"6","(-3150,4550)","0","mstr_standard","I118";
;
HDL_TAP"TRUE"
BODY_TYPE"PLUMBING"
CDS_LIB"mstr_standard";
"B \NAC \NWC"3;
"S \NAC"
BN"11"121;
%"TAP"
"6","(-3150,4500)","0","mstr_standard","I119";
;
HDL_TAP"TRUE"
BODY_TYPE"PLUMBING"
CDS_LIB"mstr_standard";
"B \NAC \NWC"3;
"S \NAC"
BN"10"120;
%"PVTT_ABC"
"1","(-950,2700)","0","mstr_symbols","I12";
;
HDL_POWER"PVTT_ABC"
ROOM"DDR4_CH_B"
BODY_TYPE"PLUMBING"
CDS_LIB"mstr_symbols"
BOM_COST"MEM"
VOLTAGE"0.6V";
"G\NAC"13;
%"TAP"
"6","(-3150,4450)","0","mstr_standard","I120";
;
HDL_TAP"TRUE"
BODY_TYPE"PLUMBING"
CDS_LIB"mstr_standard";
"B \NAC \NWC"3;
"S \NAC"
BN"9"118;
%"TAP"
"6","(-3150,4400)","0","mstr_standard","I121";
;
HDL_TAP"TRUE"
BODY_TYPE"PLUMBING"
CDS_LIB"mstr_standard";
"B \NAC \NWC"3;
"S \NAC"
BN"8"117;
%"TAP"
"6","(-3150,4350)","0","mstr_standard","I122";
;
HDL_TAP"TRUE"
BODY_TYPE"PLUMBING"
CDS_LIB"mstr_standard";
"B \NAC \NWC"3;
"S \NAC"
BN"7"116;
%"TAP"
"6","(-3150,4300)","0","mstr_standard","I123";
;
HDL_TAP"TRUE"
BODY_TYPE"PLUMBING"
CDS_LIB"mstr_standard";
"B \NAC \NWC"3;
"S \NAC"
BN"6"115;
%"TAP"
"6","(-3150,4250)","0","mstr_standard","I124";
;
HDL_TAP"TRUE"
BODY_TYPE"PLUMBING"
CDS_LIB"mstr_standard";
"B \NAC \NWC"3;
"S \NAC"
BN"5"114;
%"TAP"
"6","(-3150,4200)","0","mstr_standard","I125";
;
HDL_TAP"TRUE"
BODY_TYPE"PLUMBING"
CDS_LIB"mstr_standard";
"B \NAC \NWC"3;
"S \NAC"
BN"4"113;
%"TAP"
"6","(-3150,4150)","0","mstr_standard","I126";
;
HDL_TAP"TRUE"
BODY_TYPE"PLUMBING"
CDS_LIB"mstr_standard";
"B \NAC \NWC"3;
"S \NAC"
BN"3"112;
%"TAP"
"6","(-3150,4100)","0","mstr_standard","I128";
;
HDL_TAP"TRUE"
BODY_TYPE"PLUMBING"
CDS_LIB"mstr_standard";
"B \NAC \NWC"3;
"S \NAC"
BN"2"119;
%"TAP"
"6","(-3150,4050)","0","mstr_standard","I129";
;
HDL_TAP"TRUE"
BODY_TYPE"PLUMBING"
CDS_LIB"mstr_standard";
"B \NAC \NWC"3;
"S \NAC"
BN"1"38;
%"PVDDQ_ABC"
"1","(-1150,2550)","0","mstr_symbols","I13";
;
HDL_POWER"PVDDQ_ABC"
ROOM"DDR4_CH_B"
BODY_TYPE"PLUMBING"
CDS_LIB"mstr_symbols"
BOM_COST"MEM"
VOLTAGE"1.2V";
"G\NAC"14;
%"TAP"
"6","(-3150,4000)","0","mstr_standard","I130";
;
HDL_TAP"TRUE"
BODY_TYPE"PLUMBING"
CDS_LIB"mstr_standard";
"B \NAC \NWC"3;
"S \NAC"
BN"0"37;
%"TAP"
"6","(-3150,3900)","0","mstr_standard","I131";
;
HDL_TAP"TRUE"
BODY_TYPE"PLUMBING"
CDS_LIB"mstr_standard";
"B \NAC \NWC"9;
"S \NAC"
BN"1"32;
%"TAP"
"6","(-3150,3850)","0","mstr_standard","I132";
;
HDL_TAP"TRUE"
BODY_TYPE"PLUMBING"
CDS_LIB"mstr_standard";
"B \NAC \NWC"9;
"S \NAC"
BN"0"50;
%"TAP"
"6","(-3150,3750)","0","mstr_standard","I133";
;
HDL_TAP"TRUE"
BODY_TYPE"PLUMBING"
CDS_LIB"mstr_standard";
"B \NAC \NWC"10;
"S \NAC"
BN"0"48;
%"TAP"
"6","(-3150,3800)","0","mstr_standard","I134";
;
HDL_TAP"TRUE"
BODY_TYPE"PLUMBING"
CDS_LIB"mstr_standard";
"B \NAC \NWC"10;
"S \NAC"
BN"1"49;
%"TAP"
"6","(-3150,2800)","0","mstr_standard","I138";
;
HDL_TAP"TRUE"
BODY_TYPE"PLUMBING"
CDS_LIB"mstr_standard";
"B \NAC \NWC"12;
"S \NAC"
BN"7"51;
%"TAP"
"6","(-3150,2750)","0","mstr_standard","I139";
;
HDL_TAP"TRUE"
BODY_TYPE"PLUMBING"
CDS_LIB"mstr_standard";
"B \NAC \NWC"12;
"S \NAC"
BN"6"39;
%"TAP"
"6","(900,4600)","2","mstr_standard","I14";
;
HDL_TAP"TRUE"
BODY_TYPE"PLUMBING"
CDS_LIB"mstr_standard";
"B \NAC \NWC"2;
"S \NAC"
BN"12"159;
%"TAP"
"6","(-3150,2700)","0","mstr_standard","I140";
;
HDL_TAP"TRUE"
BODY_TYPE"PLUMBING"
CDS_LIB"mstr_standard";
"B \NAC \NWC"12;
"S \NAC"
BN"5"40;
%"TAP"
"6","(-3150,2650)","0","mstr_standard","I141";
;
HDL_TAP"TRUE"
BODY_TYPE"PLUMBING"
CDS_LIB"mstr_standard";
"B \NAC \NWC"12;
"S \NAC"
BN"4"41;
%"TAP"
"6","(-3150,2600)","0","mstr_standard","I142";
;
HDL_TAP"TRUE"
BODY_TYPE"PLUMBING"
CDS_LIB"mstr_standard";
"B \NAC \NWC"12;
"S \NAC"
BN"3"42;
%"TAP"
"6","(-3150,2550)","0","mstr_standard","I143";
;
HDL_TAP"TRUE"
BODY_TYPE"PLUMBING"
CDS_LIB"mstr_standard";
"B \NAC \NWC"12;
"S \NAC"
BN"2"43;
%"TAP"
"6","(-3150,2500)","0","mstr_standard","I144";
;
HDL_TAP"TRUE"
BODY_TYPE"PLUMBING"
CDS_LIB"mstr_standard";
"B \NAC \NWC"12;
"S \NAC"
BN"1"44;
%"TAP"
"6","(-3150,2450)","0","mstr_standard","I145";
;
HDL_TAP"TRUE"
BODY_TYPE"PLUMBING"
CDS_LIB"mstr_standard";
"B \NAC \NWC"12;
"S \NAC"
BN"0"45;
%"TAP"
"6","(900,4700)","2","mstr_standard","I15";
;
HDL_TAP"TRUE"
BODY_TYPE"PLUMBING"
CDS_LIB"mstr_standard";
"B \NAC \NWC"2;
"S \NAC"
BN"13"161;
%"TAP"
"6","(-3150,3100)","0","mstr_standard","I152";
;
HDL_TAP"TRUE"
BODY_TYPE"PLUMBING"
CDS_LIB"mstr_standard";
"B \NAC \NWC"6;
"S \NAC"
BN"3"46;
%"TAP"
"6","(-3150,3050)","0","mstr_standard","I154";
;
HDL_TAP"TRUE"
BODY_TYPE"PLUMBING"
CDS_LIB"mstr_standard";
"B \NAC \NWC"6;
"S \NAC"
BN"2"55;
%"TAP"
"6","(-3150,2950)","0","mstr_standard","I155";
;
HDL_TAP"TRUE"
BODY_TYPE"PLUMBING"
CDS_LIB"mstr_standard";
"B \NAC \NWC"7;
"S \NAC"
BN"3"54;
%"TAP"
"6","(-3150,2900)","0","mstr_standard","I157";
;
HDL_TAP"TRUE"
BODY_TYPE"PLUMBING"
CDS_LIB"mstr_standard";
"B \NAC \NWC"7;
"S \NAC"
BN"2"52;
%"TAP"
"6","(-3150,3350)","0","mstr_standard","I158";
;
HDL_TAP"TRUE"
BODY_TYPE"PLUMBING"
CDS_LIB"mstr_standard";
"B \NAC \NWC"8;
"S \NAC"
BN"7"56;
%"TAP"
"6","(-3150,3300)","0","mstr_standard","I159";
;
HDL_TAP"TRUE"
BODY_TYPE"PLUMBING"
CDS_LIB"mstr_standard";
"B \NAC \NWC"8;
"S \NAC"
BN"6"35;
%"TAP"
"6","(700,4750)","2","mstr_standard","I16";
;
HDL_TAP"TRUE"
BODY_TYPE"PLUMBING"
CDS_LIB"mstr_standard";
"B \NAC \NWC"1;
"S \NAC"
BN"13"162;
%"TAP"
"6","(-3150,3250)","0","mstr_standard","I160";
;
HDL_TAP"TRUE"
BODY_TYPE"PLUMBING"
CDS_LIB"mstr_standard";
"B \NAC \NWC"8;
"S \NAC"
BN"5"36;
%"TAP"
"6","(-3150,3200)","0","mstr_standard","I161";
;
HDL_TAP"TRUE"
BODY_TYPE"PLUMBING"
CDS_LIB"mstr_standard";
"B \NAC \NWC"8;
"S \NAC"
BN"4"53;
%"TAP"
"6","(-3150,3650)","0","mstr_standard","I163";
;
HDL_TAP"TRUE"
BODY_TYPE"PLUMBING"
CDS_LIB"mstr_standard";
"B \NAC \NWC"11;
"S \NAC"
BN"3"47;
%"TAP"
"6","(-3150,3550)","0","mstr_standard","I164";
;
HDL_TAP"TRUE"
BODY_TYPE"PLUMBING"
CDS_LIB"mstr_standard";
"B \NAC \NWC"11;
"S \NAC"
BN"2"34;
%"TAP"
"6","(-3350,3600)","0","mstr_standard","I165";
;
HDL_TAP"TRUE"
BODY_TYPE"PLUMBING"
CDS_LIB"mstr_standard";
"B \NAC \NWC"5;
"S \NAC"
BN"3"33;
%"TAP"
"6","(-3350,3500)","0","mstr_standard","I166";
;
HDL_TAP"TRUE"
BODY_TYPE"PLUMBING"
CDS_LIB"mstr_standard";
"B \NAC \NWC"5;
"S \NAC"
BN"2"57;
%"TAP"
"6","(700,4650)","2","mstr_standard","I17";
;
HDL_TAP"TRUE"
BODY_TYPE"PLUMBING"
CDS_LIB"mstr_standard";
"B \NAC \NWC"1;
"S \NAC"
BN"12"160;
%"SCONN288_H44441003"
"4","(-100,2000)","0","mstr_sconn","I171";
;
CDS_SEC"4"
ROOM"DDR4_CH_C1"
CDS_LOCATION"J6U2"
SEC"4"
SEC_TYPE"PIP"
CDS_LIB"mstr_sconn"
BOM_COST"MEM"
PACK_TYPE"PIP"
MATERIAL"SCONN"
PART_NUMBER"H44441-003"
LOCATION"J6U2";
"VDD<0>"
$PN"236"14;
"VDD<6>"
$PN"220"14;
"VDD<10>"
$PN"209"14;
"VDD<13>"
$PN"92"14;
"VDD<16>"
$PN"85"14;
"VDD<19>"
$PN"76"14;
"VDD<23>"
$PN"64"14;
"VDD<25>"
$PN"59"14;
"VTT<0>"
$PN"221"13;
"12V<1>"
$PN"1"20;
"12V<0>"
$PN"145"20;
"VDD<24>"
$PN"61"14;
"VDD<22>"
$PN"67"14;
"VDD<21>"
$PN"70"14;
"VDD<20>"
$PN"73"14;
"VDD<18>"
$PN"80"14;
"VDD<17>"
$PN"83"14;
"VDD<15>"
$PN"88"14;
"VDD<14>"
$PN"90"14;
"VDD<12>"
$PN"204"14;
"VDD<11>"
$PN"206"14;
"VDD<9>"
$PN"212"14;
"VDD<8>"
$PN"215"14;
"VDD<7>"
$PN"217"14;
"VDD<5>"
$PN"223"14;
"VDD<4>"
$PN"226"14;
"VDD<3>"
$PN"229"14;
"VDD<2>"
$PN"231"14;
"VDD<1>"
$PN"233"14;
"VPP<4>"
$PN"142"17;
"VPP<3>"
$PN"143"17;
"VPP<2>"
$PN"288"17;
"VPP<1>"
$PN"286"17;
"VPP<0>"
$PN"287"17;
"VTT<1>"
$PN"77"13;
%"GND"
"1","(2500,1300)","2","mstr_symbols","I172";
;
HDL_POWER"GND"
ROOM"DDR4_CH_B"
BODY_TYPE"PLUMBING"
BOM_COST"MEM"
SIZE"1B"
CDS_LIB"mstr_symbols"
VOLTAGE"0";
"A\NAC"15;
%"CAP_A"
"1","(-4650,1500)","2","dev_discrete","I176";
;
ROOM"DDR4_CH_B"
SEC"1"
SEC_TYPE"0402V"
CDS_SEC"1"
CDS_LIB"dev_discrete"
BOM_COST"MEM"
CDS_LOCATION"C6U17"
MATERIAL"X7R"
VOLTAGE"25V"
PACK_TYPE"0402V"
TOLERANCE"10%"
VALUE"0.01UF"
PART_NUMBER"A36096-045"
LOCATION"C6U17";
"B"
$PN"2"16;
"A"
$PN"1"22;
%"GND"
"1","(-4650,1250)","0","mstr_symbols","I177";
;
HDL_POWER"GND"
ROOM"DDR4_CH_B"
BODY_TYPE"PLUMBING"
CDS_LIB"mstr_symbols"
BOM_COST"MEM"
SIZE"1B"
VOLTAGE"0";
"A\NAC"16;
%"PVPP_ABC"
"1","(-800,3000)","0","mstr_symbols","I178";
;
HDL_POWER"PVPP_ABC"
ROOM"DDR4_CH_B"
BODY_TYPE"PLUMBING"
CDS_LIB"mstr_symbols"
BOM_COST"MEM"
VOLTAGE"2.5V";
"G\NAC"17;
%"PVPP_ABC"
"1","(-4650,2250)","0","mstr_symbols","I179";
;
HDL_POWER"PVPP_ABC"
ROOM"DDR4_CH_B"
BODY_TYPE"PLUMBING"
CDS_LIB"mstr_symbols"
BOM_COST"MEM"
VOLTAGE"2.5V";
"G\NAC"18;
%"TAP"
"6","(700,4550)","2","mstr_standard","I18";
;
HDL_TAP"TRUE"
BODY_TYPE"PLUMBING"
CDS_LIB"mstr_standard";
"B \NAC \NWC"1;
"S \NAC"
BN"11"158;
%"GND"
"1","(-4650,1850)","0","mstr_symbols","I184";
;
HDL_POWER"GND"
ROOM"DDR4_CH_B"
BODY_TYPE"PLUMBING"
SIZE"1B"
BOM_COST"MEM"
CDS_LIB"mstr_symbols"
VOLTAGE"0";
"A\NAC"19;
%"P12V_NVDIMM_ABC"
"1","(600,3075)","0","mstr_symbols","I185";
;
HDL_POWER"P12V_NVDIMM_ABC"
BODY_TYPE"PLUMBING"
CDS_LIB"mstr_symbols"
VOLTAGE"12.0";
"G\NAC"20;
%"TAP"
"6","(900,4400)","2","mstr_standard","I19";
;
HDL_TAP"TRUE"
BODY_TYPE"PLUMBING"
CDS_LIB"mstr_standard";
"B \NAC \NWC"2;
"S \NAC"
BN"10"155;
%"TAP"
"6","(900,4500)","2","mstr_standard","I20";
;
HDL_TAP"TRUE"
BODY_TYPE"PLUMBING"
CDS_LIB"mstr_standard";
"B \NAC \NWC"2;
"S \NAC"
BN"11"157;
%"TAP"
"6","(900,4300)","2","mstr_standard","I21";
;
HDL_TAP"TRUE"
BODY_TYPE"PLUMBING"
CDS_LIB"mstr_standard";
"B \NAC \NWC"2;
"S \NAC"
BN"9"174;
%"TAP"
"6","(700,4450)","2","mstr_standard","I22";
;
HDL_TAP"TRUE"
BODY_TYPE"PLUMBING"
CDS_LIB"mstr_standard";
"B \NAC \NWC"1;
"S \NAC"
BN"10"156;
%"TAP"
"6","(700,4350)","2","mstr_standard","I23";
;
HDL_TAP"TRUE"
BODY_TYPE"PLUMBING"
CDS_LIB"mstr_standard";
"B \NAC \NWC"1;
"S \NAC"
BN"9"175;
%"TAP"
"6","(900,4100)","2","mstr_standard","I24";
;
HDL_TAP"TRUE"
BODY_TYPE"PLUMBING"
CDS_LIB"mstr_standard";
"B \NAC \NWC"2;
"S \NAC"
BN"7"170;
%"TAP"
"6","(900,4200)","2","mstr_standard","I25";
;
HDL_TAP"TRUE"
BODY_TYPE"PLUMBING"
CDS_LIB"mstr_standard";
"B \NAC \NWC"2;
"S \NAC"
BN"8"172;
%"TAP"
"6","(700,4250)","2","mstr_standard","I26";
;
HDL_TAP"TRUE"
BODY_TYPE"PLUMBING"
CDS_LIB"mstr_standard";
"B \NAC \NWC"1;
"S \NAC"
BN"8"173;
%"TAP"
"6","(700,4150)","2","mstr_standard","I27";
;
HDL_TAP"TRUE"
BODY_TYPE"PLUMBING"
CDS_LIB"mstr_standard";
"B \NAC \NWC"1;
"S \NAC"
BN"7"171;
%"TAP"
"6","(700,4050)","2","mstr_standard","I28";
;
HDL_TAP"TRUE"
BODY_TYPE"PLUMBING"
CDS_LIB"mstr_standard";
"B \NAC \NWC"1;
"S \NAC"
BN"6"154;
%"TAP"
"6","(900,3900)","2","mstr_standard","I29";
;
HDL_TAP"TRUE"
BODY_TYPE"PLUMBING"
CDS_LIB"mstr_standard";
"B \NAC \NWC"2;
"S \NAC"
BN"5"151;
%"TAP"
"6","(900,5100)","2","mstr_standard","I3";
;
HDL_TAP"TRUE"
BODY_TYPE"PLUMBING"
CDS_LIB"mstr_standard";
"B \NAC \NWC"2;
"S \NAC"
BN"17"169;
%"TAP"
"6","(900,4000)","2","mstr_standard","I30";
;
HDL_TAP"TRUE"
BODY_TYPE"PLUMBING"
CDS_LIB"mstr_standard";
"B \NAC \NWC"2;
"S \NAC"
BN"6"153;
%"TAP"
"6","(900,3800)","2","mstr_standard","I31";
;
HDL_TAP"TRUE"
BODY_TYPE"PLUMBING"
CDS_LIB"mstr_standard";
"B \NAC \NWC"2;
"S \NAC"
BN"4"149;
%"TAP"
"6","(700,3950)","2","mstr_standard","I32";
;
HDL_TAP"TRUE"
BODY_TYPE"PLUMBING"
CDS_LIB"mstr_standard";
"B \NAC \NWC"1;
"S \NAC"
BN"5"152;
%"TAP"
"6","(700,3850)","2","mstr_standard","I33";
;
HDL_TAP"TRUE"
BODY_TYPE"PLUMBING"
CDS_LIB"mstr_standard";
"B \NAC \NWC"1;
"S \NAC"
BN"4"150;
%"TAP"
"6","(700,3750)","2","mstr_standard","I34";
;
HDL_TAP"TRUE"
BODY_TYPE"PLUMBING"
CDS_LIB"mstr_standard";
"B \NAC \NWC"1;
"S \NAC"
BN"3"148;
%"TAP"
"6","(900,3500)","2","mstr_standard","I35";
;
HDL_TAP"TRUE"
BODY_TYPE"PLUMBING"
CDS_LIB"mstr_standard";
"B \NAC \NWC"2;
"S \NAC"
BN"1"143;
%"TAP"
"6","(900,3600)","2","mstr_standard","I36";
;
HDL_TAP"TRUE"
BODY_TYPE"PLUMBING"
CDS_LIB"mstr_standard";
"B \NAC \NWC"2;
"S \NAC"
BN"2"145;
%"TAP"
"6","(900,3700)","2","mstr_standard","I37";
;
HDL_TAP"TRUE"
BODY_TYPE"PLUMBING"
CDS_LIB"mstr_standard";
"B \NAC \NWC"2;
"S \NAC"
BN"3"147;
%"TAP"
"6","(700,3650)","2","mstr_standard","I38";
;
HDL_TAP"TRUE"
BODY_TYPE"PLUMBING"
CDS_LIB"mstr_standard";
"B \NAC \NWC"1;
"S \NAC"
BN"2"146;
%"TAP"
"6","(700,3550)","2","mstr_standard","I39";
;
HDL_TAP"TRUE"
BODY_TYPE"PLUMBING"
CDS_LIB"mstr_standard";
"B \NAC \NWC"1;
"S \NAC"
BN"1"144;
%"TAP"
"6","(700,5150)","2","mstr_standard","I4";
;
HDL_TAP"TRUE"
BODY_TYPE"PLUMBING"
CDS_LIB"mstr_standard";
"B \NAC \NWC"1;
"S \NAC"
BN"17"176;
%"TAP"
"6","(900,3400)","2","mstr_standard","I40";
;
HDL_TAP"TRUE"
BODY_TYPE"PLUMBING"
CDS_LIB"mstr_standard";
"B \NAC \NWC"2;
"S \NAC"
BN"0"141;
%"TAP"
"6","(700,3450)","2","mstr_standard","I41";
;
HDL_TAP"TRUE"
BODY_TYPE"PLUMBING"
CDS_LIB"mstr_standard";
"B \NAC \NWC"1;
"S \NAC"
BN"0"142;
%"SCONN288_H44441003"
"3","(1800,2600)","0","mstr_sconn","I43";
;
CDS_SEC"3"
ROOM"DDR4_CH_C1"
CDS_LOCATION"J6U2"
SEC"3"
SEC_TYPE"PIP"
CDS_LIB"mstr_sconn"
BOM_COST"MEM"
PACK_TYPE"PIP"
MATERIAL"SCONN"
PART_NUMBER"H44441-003"
LOCATION"J6U2";
"VSS<46>"
$PN"147"15;
"VSS<45>"
$PN"149"15;
"VSS<87>"
$PN"15"21;
"VSS<86>"
$PN"17"21;
"VSS<85>"
$PN"20"21;
"VSS<84>"
$PN"22"21;
"VSS<83>"
$PN"24"21;
"VSS<82>"
$PN"26"21;
"VSS<81>"
$PN"28"21;
"VSS<80>"
$PN"31"21;
"VSS<79>"
$PN"33"21;
"VSS<78>"
$PN"35"21;
"VSS<77>"
$PN"37"21;
"VSS<76>"
$PN"39"21;
"VSS<75>"
$PN"42"21;
"VSS<74>"
$PN"44"21;
"VSS<73>"
$PN"46"21;
"VSS<72>"
$PN"48"21;
"VSS<71>"
$PN"50"21;
"VSS<70>"
$PN"53"21;
"VSS<69>"
$PN"55"21;
"VSS<68>"
$PN"57"21;
"VSS<67>"
$PN"94"21;
"VSS<66>"
$PN"96"21;
"VSS<65>"
$PN"98"21;
"VSS<64>"
$PN"101"21;
"VSS<63>"
$PN"103"21;
"VSS<62>"
$PN"105"21;
"VSS<61>"
$PN"107"21;
"VSS<60>"
$PN"109"21;
"VSS<59>"
$PN"112"21;
"VSS<58>"
$PN"114"21;
"VSS<57>"
$PN"116"21;
"VSS<56>"
$PN"118"21;
"VSS<55>"
$PN"120"21;
"VSS<54>"
$PN"123"21;
"VSS<53>"
$PN"125"21;
"VSS<52>"
$PN"127"21;
"VSS<51>"
$PN"129"21;
"VSS<50>"
$PN"131"21;
"VSS<49>"
$PN"134"21;
"VSS<48>"
$PN"136"21;
"VSS<47>"
$PN"138"21;
"VSS<44>"
$PN"151"15;
"VSS<43>"
$PN"154"15;
"VSS<42>"
$PN"156"15;
"VSS<41>"
$PN"158"15;
"VSS<40>"
$PN"160"15;
"VSS<39>"
$PN"162"15;
"VSS<38>"
$PN"165"15;
"VSS<37>"
$PN"167"15;
"VSS<36>"
$PN"169"15;
"VSS<35>"
$PN"171"15;
"VSS<34>"
$PN"173"15;
"VSS<33>"
$PN"176"15;
"VSS<32>"
$PN"178"15;
"VSS<31>"
$PN"180"15;
"VSS<30>"
$PN"182"15;
"VSS<29>"
$PN"184"15;
"VSS<28>"
$PN"187"15;
"VSS<27>"
$PN"189"15;
"VSS<26>"
$PN"191"15;
"VSS<25>"
$PN"193"15;
"VSS<24>"
$PN"195"15;
"VSS<23>"
$PN"198"15;
"VSS<22>"
$PN"200"15;
"VSS<21>"
$PN"202"15;
"VSS<20>"
$PN"239"15;
"VSS<19>"
$PN"241"15;
"VSS<18>"
$PN"243"15;
"VSS<17>"
$PN"246"15;
"VSS<16>"
$PN"248"15;
"VSS<15>"
$PN"250"15;
"VSS<14>"
$PN"252"15;
"VSS<13>"
$PN"254"15;
"VSS<12>"
$PN"257"15;
"VSS<11>"
$PN"259"15;
"VSS<10>"
$PN"261"15;
"VSS<9>"
$PN"263"15;
"VSS<8>"
$PN"265"15;
"VSS<7>"
$PN"268"15;
"VSS<6>"
$PN"270"15;
"VSS<5>"
$PN"272"15;
"VSS<4>"
$PN"274"15;
"VSS<3>"
$PN"276"15;
"VSS<2>"
$PN"279"15;
"VSS<1>"
$PN"281"15;
"VSS<0>"
$PN"283"15;
"VSS<88>"
$PN"13"21;
"VSS<89>"
$PN"11"21;
"VSS<90>"
$PN"9"21;
"VSS<91>"
$PN"6"21;
"VSS<92>"
$PN"4"21;
"VSS<93>"
$PN"2"21;
%"GND"
"1","(1100,1300)","2","mstr_symbols","I44";
;
HDL_POWER"GND"
ROOM"DDR4_CH_B"
BODY_TYPE"PLUMBING"
BOM_COST"MEM"
SIZE"1B"
CDS_LIB"mstr_symbols"
VOLTAGE"0";
"A\NAC"21;
%"TAP"
"6","(-1650,4850)","2","mstr_standard","I46";
;
HDL_TAP"TRUE"
BODY_TYPE"PLUMBING"
CDS_LIB"mstr_standard";
"B \NAC \NWC"4;
"S \NAC"
BN"63"136;
%"TAP"
"6","(-1650,4800)","2","mstr_standard","I47";
;
HDL_TAP"TRUE"
BODY_TYPE"PLUMBING"
CDS_LIB"mstr_standard";
"B \NAC \NWC"4;
"S \NAC"
BN"62"137;
%"TAP"
"6","(-1650,4650)","2","mstr_standard","I48";
;
HDL_TAP"TRUE"
BODY_TYPE"PLUMBING"
CDS_LIB"mstr_standard";
"B \NAC \NWC"4;
"S \NAC"
BN"59"140;
%"TAP"
"6","(-1650,4700)","2","mstr_standard","I49";
;
HDL_TAP"TRUE"
BODY_TYPE"PLUMBING"
CDS_LIB"mstr_standard";
"B \NAC \NWC"4;
"S \NAC"
BN"60"139;
%"TAP"
"6","(700,5050)","2","mstr_standard","I5";
;
HDL_TAP"TRUE"
BODY_TYPE"PLUMBING"
CDS_LIB"mstr_standard";
"B \NAC \NWC"1;
"S \NAC"
BN"16"168;
%"TAP"
"6","(-1650,4750)","2","mstr_standard","I50";
;
HDL_TAP"TRUE"
BODY_TYPE"PLUMBING"
CDS_LIB"mstr_standard";
"B \NAC \NWC"4;
"S \NAC"
BN"61"138;
%"TAP"
"6","(-1650,4550)","2","mstr_standard","I51";
;
HDL_TAP"TRUE"
BODY_TYPE"PLUMBING"
CDS_LIB"mstr_standard";
"B \NAC \NWC"4;
"S \NAC"
BN"57"127;
%"TAP"
"6","(-1650,4600)","2","mstr_standard","I52";
;
HDL_TAP"TRUE"
BODY_TYPE"PLUMBING"
CDS_LIB"mstr_standard";
"B \NAC \NWC"4;
"S \NAC"
BN"58"128;
%"TAP"
"6","(-1650,4400)","2","mstr_standard","I53";
;
HDL_TAP"TRUE"
BODY_TYPE"PLUMBING"
CDS_LIB"mstr_standard";
"B \NAC \NWC"4;
"S \NAC"
BN"54"129;
%"TAP"
"6","(-1650,4450)","2","mstr_standard","I54";
;
HDL_TAP"TRUE"
BODY_TYPE"PLUMBING"
CDS_LIB"mstr_standard";
"B \NAC \NWC"4;
"S \NAC"
BN"55"126;
%"TAP"
"6","(-1650,4500)","2","mstr_standard","I55";
;
HDL_TAP"TRUE"
BODY_TYPE"PLUMBING"
CDS_LIB"mstr_standard";
"B \NAC \NWC"4;
"S \NAC"
BN"56"125;
%"TAP"
"6","(-1650,4300)","2","mstr_standard","I56";
;
HDL_TAP"TRUE"
BODY_TYPE"PLUMBING"
CDS_LIB"mstr_standard";
"B \NAC \NWC"4;
"S \NAC"
BN"52"131;
%"TAP"
"6","(-1650,4350)","2","mstr_standard","I57";
;
HDL_TAP"TRUE"
BODY_TYPE"PLUMBING"
CDS_LIB"mstr_standard";
"B \NAC \NWC"4;
"S \NAC"
BN"53"130;
%"TAP"
"6","(-1650,4250)","2","mstr_standard","I58";
;
HDL_TAP"TRUE"
BODY_TYPE"PLUMBING"
CDS_LIB"mstr_standard";
"B \NAC \NWC"4;
"S \NAC"
BN"51"132;
%"TAP"
"6","(-1650,4200)","2","mstr_standard","I59";
;
HDL_TAP"TRUE"
BODY_TYPE"PLUMBING"
CDS_LIB"mstr_standard";
"B \NAC \NWC"4;
"S \NAC"
BN"50"133;
%"TAP"
"6","(900,4900)","2","mstr_standard","I6";
;
HDL_TAP"TRUE"
BODY_TYPE"PLUMBING"
CDS_LIB"mstr_standard";
"B \NAC \NWC"2;
"S \NAC"
BN"15"165;
%"TAP"
"6","(-1650,4150)","2","mstr_standard","I60";
;
HDL_TAP"TRUE"
BODY_TYPE"PLUMBING"
CDS_LIB"mstr_standard";
"B \NAC \NWC"4;
"S \NAC"
BN"49"134;
%"SCONN288_H44441003"
"2","(0,4300)","0","mstr_sconn","I61";
;
CDS_SEC"2"
ROOM"DDR4_CH_C1"
CDS_LOCATION"J6U2"
SEC"2"
SEC_TYPE"PIP"
CDS_LIB"mstr_sconn"
BOM_COST"MEM"
PACK_TYPE"PIP"
MATERIAL"SCONN"
PART_NUMBER"H44441-003"
LOCATION"J6U2";
"DQS0N"
$PN"152"141;
"DQS0P"
$PN"153"142;
"DQS10N"
$PN"19"155;
"DQS10P"
$PN"18"156;
"DQS11N"
$PN"30"157;
"DQS11P"
$PN"29"158;
"DQS12N"
$PN"41"159;
"DQS12P"
$PN"40"160;
"DQS13N"
$PN"100"161;
"DQS13P"
$PN"99"162;
"DQS14N"
$PN"111"163;
"DQS14P"
$PN"110"164;
"DQS15N"
$PN"122"165;
"DQS15P"
$PN"121"166;
"DQS16N"
$PN"133"167;
"DQS16P"
$PN"132"168;
"DQS17N"
$PN"52"169;
"DQS17P"
$PN"51"176;
"DQS1N"
$PN"163"143;
"DQS1P"
$PN"164"144;
"DQS2N"
$PN"174"145;
"DQS2P"
$PN"175"146;
"DQS3N"
$PN"185"147;
"DQS3P"
$PN"186"148;
"DQS4N"
$PN"244"149;
"DQS4P"
$PN"245"150;
"DQS5N"
$PN"255"151;
"DQS5P"
$PN"256"152;
"DQS6N"
$PN"266"153;
"DQS6P"
$PN"267"154;
"DQS7N"
$PN"277"170;
"DQS7P"
$PN"278"171;
"DQS8N"
$PN"196"172;
"DQS8P"
$PN"197"173;
"DQS9N"
$PN"8"174;
"DQS9P"
$PN"7"175;
%"TAP"
"6","(-1650,4000)","2","mstr_standard","I62";
;
HDL_TAP"TRUE"
BODY_TYPE"PLUMBING"
CDS_LIB"mstr_standard";
"B \NAC \NWC"4;
"S \NAC"
BN"46"99;
%"TAP"
"6","(-1650,4050)","2","mstr_standard","I63";
;
HDL_TAP"TRUE"
BODY_TYPE"PLUMBING"
CDS_LIB"mstr_standard";
"B \NAC \NWC"4;
"S \NAC"
BN"47"108;
%"TAP"
"6","(-1650,4100)","2","mstr_standard","I64";
;
HDL_TAP"TRUE"
BODY_TYPE"PLUMBING"
CDS_LIB"mstr_standard";
"B \NAC \NWC"4;
"S \NAC"
BN"48"135;
%"TAP"
"6","(-1650,3950)","2","mstr_standard","I65";
;
HDL_TAP"TRUE"
BODY_TYPE"PLUMBING"
CDS_LIB"mstr_standard";
"B \NAC \NWC"4;
"S \NAC"
BN"45"100;
%"TAP"
"6","(-1650,3900)","2","mstr_standard","I66";
;
HDL_TAP"TRUE"
BODY_TYPE"PLUMBING"
CDS_LIB"mstr_standard";
"B \NAC \NWC"4;
"S \NAC"
BN"44"101;
%"TAP"
"6","(-1650,3850)","2","mstr_standard","I67";
;
HDL_TAP"TRUE"
BODY_TYPE"PLUMBING"
CDS_LIB"mstr_standard";
"B \NAC \NWC"4;
"S \NAC"
BN"43"102;
%"TAP"
"6","(-1650,3800)","2","mstr_standard","I68";
;
HDL_TAP"TRUE"
BODY_TYPE"PLUMBING"
CDS_LIB"mstr_standard";
"B \NAC \NWC"4;
"S \NAC"
BN"42"103;
%"TAP"
"6","(-1650,3750)","2","mstr_standard","I69";
;
HDL_TAP"TRUE"
BODY_TYPE"PLUMBING"
CDS_LIB"mstr_standard";
"B \NAC \NWC"4;
"S \NAC"
BN"41"104;
%"TAP"
"6","(900,5000)","2","mstr_standard","I7";
;
HDL_TAP"TRUE"
BODY_TYPE"PLUMBING"
CDS_LIB"mstr_standard";
"B \NAC \NWC"2;
"S \NAC"
BN"16"167;
%"TAP"
"6","(-1650,3650)","2","mstr_standard","I70";
;
HDL_TAP"TRUE"
BODY_TYPE"PLUMBING"
CDS_LIB"mstr_standard";
"B \NAC \NWC"4;
"S \NAC"
BN"39"106;
%"TAP"
"6","(-1650,3700)","2","mstr_standard","I71";
;
HDL_TAP"TRUE"
BODY_TYPE"PLUMBING"
CDS_LIB"mstr_standard";
"B \NAC \NWC"4;
"S \NAC"
BN"40"105;
%"TAP"
"6","(-1650,3500)","2","mstr_standard","I72";
;
HDL_TAP"TRUE"
BODY_TYPE"PLUMBING"
CDS_LIB"mstr_standard";
"B \NAC \NWC"4;
"S \NAC"
BN"36"98;
%"TAP"
"6","(-1650,3550)","2","mstr_standard","I73";
;
HDL_TAP"TRUE"
BODY_TYPE"PLUMBING"
CDS_LIB"mstr_standard";
"B \NAC \NWC"4;
"S \NAC"
BN"37"91;
%"TAP"
"6","(-1650,3600)","2","mstr_standard","I74";
;
HDL_TAP"TRUE"
BODY_TYPE"PLUMBING"
CDS_LIB"mstr_standard";
"B \NAC \NWC"4;
"S \NAC"
BN"38"107;
%"TAP"
"6","(-1650,3400)","2","mstr_standard","I75";
;
HDL_TAP"TRUE"
BODY_TYPE"PLUMBING"
CDS_LIB"mstr_standard";
"B \NAC \NWC"4;
"S \NAC"
BN"34"92;
%"TAP"
"6","(-1650,3450)","2","mstr_standard","I76";
;
HDL_TAP"TRUE"
BODY_TYPE"PLUMBING"
CDS_LIB"mstr_standard";
"B \NAC \NWC"4;
"S \NAC"
BN"35"97;
%"TAP"
"6","(-1650,3350)","2","mstr_standard","I77";
;
HDL_TAP"TRUE"
BODY_TYPE"PLUMBING"
CDS_LIB"mstr_standard";
"B \NAC \NWC"4;
"S \NAC"
BN"33"93;
%"TAP"
"6","(-1650,3300)","2","mstr_standard","I78";
;
HDL_TAP"TRUE"
BODY_TYPE"PLUMBING"
CDS_LIB"mstr_standard";
"B \NAC \NWC"4;
"S \NAC"
BN"32"94;
%"TAP"
"6","(-1650,3250)","2","mstr_standard","I79";
;
HDL_TAP"TRUE"
BODY_TYPE"PLUMBING"
CDS_LIB"mstr_standard";
"B \NAC \NWC"4;
"S \NAC"
BN"31"95;
%"TAP"
"6","(900,4800)","2","mstr_standard","I8";
;
HDL_TAP"TRUE"
BODY_TYPE"PLUMBING"
CDS_LIB"mstr_standard";
"B \NAC \NWC"2;
"S \NAC"
BN"14"163;
%"TAP"
"6","(-1650,3100)","2","mstr_standard","I80";
;
HDL_TAP"TRUE"
BODY_TYPE"PLUMBING"
CDS_LIB"mstr_standard";
"B \NAC \NWC"4;
"S \NAC"
BN"28"90;
%"TAP"
"6","(-1650,3150)","2","mstr_standard","I81";
;
HDL_TAP"TRUE"
BODY_TYPE"PLUMBING"
CDS_LIB"mstr_standard";
"B \NAC \NWC"4;
"S \NAC"
BN"29"89;
%"TAP"
"6","(-1650,3200)","2","mstr_standard","I82";
;
HDL_TAP"TRUE"
BODY_TYPE"PLUMBING"
CDS_LIB"mstr_standard";
"B \NAC \NWC"4;
"S \NAC"
BN"30"96;
%"TAP"
"6","(-1650,3050)","2","mstr_standard","I83";
;
HDL_TAP"TRUE"
BODY_TYPE"PLUMBING"
CDS_LIB"mstr_standard";
"B \NAC \NWC"4;
"S \NAC"
BN"27"86;
%"TAP"
"6","(-1650,3000)","2","mstr_standard","I84";
;
HDL_TAP"TRUE"
BODY_TYPE"PLUMBING"
CDS_LIB"mstr_standard";
"B \NAC \NWC"4;
"S \NAC"
BN"26"87;
%"TAP"
"6","(-1650,2850)","2","mstr_standard","I85";
;
HDL_TAP"TRUE"
BODY_TYPE"PLUMBING"
CDS_LIB"mstr_standard";
"B \NAC \NWC"4;
"S \NAC"
BN"23"81;
%"TAP"
"6","(-1650,2950)","2","mstr_standard","I86";
;
HDL_TAP"TRUE"
BODY_TYPE"PLUMBING"
CDS_LIB"mstr_standard";
"B \NAC \NWC"4;
"S \NAC"
BN"25"79;
%"TAP"
"6","(-1650,2900)","2","mstr_standard","I87";
;
HDL_TAP"TRUE"
BODY_TYPE"PLUMBING"
CDS_LIB"mstr_standard";
"B \NAC \NWC"4;
"S \NAC"
BN"24"80;
%"TAP"
"6","(-1650,2750)","2","mstr_standard","I88";
;
HDL_TAP"TRUE"
BODY_TYPE"PLUMBING"
CDS_LIB"mstr_standard";
"B \NAC \NWC"4;
"S \NAC"
BN"21"83;
%"TAP"
"6","(-1650,2800)","2","mstr_standard","I89";
;
HDL_TAP"TRUE"
BODY_TYPE"PLUMBING"
CDS_LIB"mstr_standard";
"B \NAC \NWC"4;
"S \NAC"
BN"22"82;
%"TAP"
"6","(700,4950)","2","mstr_standard","I9";
;
HDL_TAP"TRUE"
BODY_TYPE"PLUMBING"
CDS_LIB"mstr_standard";
"B \NAC \NWC"1;
"S \NAC"
BN"15"166;
%"TAP"
"6","(-1650,2700)","2","mstr_standard","I90";
;
HDL_TAP"TRUE"
BODY_TYPE"PLUMBING"
CDS_LIB"mstr_standard";
"B \NAC \NWC"4;
"S \NAC"
BN"20"88;
%"TAP"
"6","(-1650,2650)","2","mstr_standard","I91";
;
HDL_TAP"TRUE"
BODY_TYPE"PLUMBING"
CDS_LIB"mstr_standard";
"B \NAC \NWC"4;
"S \NAC"
BN"19"84;
%"TAP"
"6","(-1650,2600)","2","mstr_standard","I92";
;
HDL_TAP"TRUE"
BODY_TYPE"PLUMBING"
CDS_LIB"mstr_standard";
"B \NAC \NWC"4;
"S \NAC"
BN"18"85;
%"TAP"
"6","(-1650,2500)","2","mstr_standard","I93";
;
HDL_TAP"TRUE"
BODY_TYPE"PLUMBING"
CDS_LIB"mstr_standard";
"B \NAC \NWC"4;
"S \NAC"
BN"16"68;
%"TAP"
"6","(-1650,2550)","2","mstr_standard","I94";
;
HDL_TAP"TRUE"
BODY_TYPE"PLUMBING"
CDS_LIB"mstr_standard";
"B \NAC \NWC"4;
"S \NAC"
BN"17"77;
%"TAP"
"6","(-1650,2350)","2","mstr_standard","I95";
;
HDL_TAP"TRUE"
BODY_TYPE"PLUMBING"
CDS_LIB"mstr_standard";
"B \NAC \NWC"4;
"S \NAC"
BN"13"70;
%"TAP"
"6","(-1650,2400)","2","mstr_standard","I96";
;
HDL_TAP"TRUE"
BODY_TYPE"PLUMBING"
CDS_LIB"mstr_standard";
"B \NAC \NWC"4;
"S \NAC"
BN"14"69;
%"TAP"
"6","(-1650,2450)","2","mstr_standard","I97";
;
HDL_TAP"TRUE"
BODY_TYPE"PLUMBING"
CDS_LIB"mstr_standard";
"B \NAC \NWC"4;
"S \NAC"
BN"15"76;
%"TAP"
"6","(-1650,2250)","2","mstr_standard","I98";
;
HDL_TAP"TRUE"
BODY_TYPE"PLUMBING"
CDS_LIB"mstr_standard";
"B \NAC \NWC"4;
"S \NAC"
BN"11"78;
%"TAP"
"6","(-1650,2300)","2","mstr_standard","I99";
;
HDL_TAP"TRUE"
BODY_TYPE"PLUMBING"
CDS_LIB"mstr_standard";
"B \NAC \NWC"4;
"S \NAC"
BN"12"71;
END.
